(kicad_pcb
	(version 20241229)
	(generator "pcbnew")
	(generator_version "9.0")
	(general
		(thickness 1.552)
		(legacy_teardrops no)
	)
	(paper "A4")
	(title_block
		(date "2023-07-25")
		(rev "1.1.4")
		(comment 9 "footprints 244-247 of 379")
	)
	(layers
		(0 "F.Cu" signal)
		(4 "In1.Cu" signal)
		(6 "In2.Cu" signal)
		(8 "In3.Cu" signal)
		(10 "In4.Cu" signal)
		(12 "In5.Cu" signal)
		(14 "In6.Cu" signal)
		(2 "B.Cu" signal)
		(9 "F.Adhes" user "F.Adhesive")
		(11 "B.Adhes" user "B.Adhesive")
		(13 "F.Paste" user)
		(15 "B.Paste" user)
		(5 "F.SilkS" user "F.Silkscreen")
		(7 "B.SilkS" user "B.Silkscreen")
		(1 "F.Mask" user)
		(3 "B.Mask" user)
		(17 "Dwgs.User" user "User.Drawings")
		(19 "Cmts.User" user "User.Comments")
		(21 "Eco1.User" user "User.Eco1")
		(23 "Eco2.User" user "User.Eco2")
		(25 "Edge.Cuts" user)
		(27 "Margin" user)
		(31 "F.CrtYd" user "F.Courtyard")
		(29 "B.CrtYd" user "B.Courtyard")
		(35 "F.Fab" user)
		(33 "B.Fab" user)
	)
	(footprint "antmicro-footprints:C_0402_1005Metric"
		(layer "B.Cu")
		(at 147.2 81.5 90)
		(descr "Capacitor SMD 0402")
		(tags "capacitor SMD 0402")
		(property "Reference" "C121"
			(at 0.96 0.33 90)
			(layer "B.SilkS")
			(effects
				(font
					(size 0.65 0.65)
					(thickness 0.15)
				)
				(justify right bottom mirror)
			)
		)
		(property "Value" "C_47p_0402"
			(at 0 -1.4 90)
			(layer "B.Fab")
			(hide yes)
			(effects
				(font
					(size 0.7 0.7)
					(thickness 0.15)
				)
				(justify right bottom mirror)
			)
		)
		(property "Datasheet" "https://www.kemet.com/en/us/capacitors/product/C0402C470J5GACTU.html"
			(at 0 0 90)
			(layer "F.Fab")
			(hide yes)
			(effects
				(font
					(size 1.27 1.27)
					(thickness 0.15)
				)
			)
		)
		(property "Description" "SMD Multilayer Ceramic Capacitor, 47 pF, 50 V, 0402 [1005 Metric], ± 5%, C0G / NP0, C Series KEMET"
			(at 0 0 90)
			(layer "F.Fab")
			(hide yes)
			(effects
				(font
					(size 1.27 1.27)
					(thickness 0.15)
				)
			)
		)
		(property "Author" "Antmicro"
			(at 228.7 -65.7 0)
			(layer "B.Fab")
			(hide yes)
			(effects
				(font
					(size 1 1)
					(thickness 0.15)
				)
				(justify mirror)
			)
		)
		(property "Dielectric" "C0G"
			(at 228.7 -65.7 0)
			(layer "B.Fab")
			(hide yes)
			(effects
				(font
					(size 1 1)
					(thickness 0.15)
				)
				(justify mirror)
			)
		)
		(property "License" "Apache-2.0"
			(at 228.7 -65.7 0)
			(layer "B.Fab")
			(hide yes)
			(effects
				(font
					(size 1 1)
					(thickness 0.15)
				)
				(justify mirror)
			)
		)
		(property "MPN" "C0402C470J5GACTU"
			(at 228.7 -65.7 0)
			(layer "B.Fab")
			(hide yes)
			(effects
				(font
					(size 1 1)
					(thickness 0.15)
				)
				(justify mirror)
			)
		)
		(property "Manufacturer" "KEMET"
			(at 228.7 -65.7 0)
			(layer "B.Fab")
			(hide yes)
			(effects
				(font
					(size 1 1)
					(thickness 0.15)
				)
				(justify mirror)
			)
		)
		(property "Val" "47p"
			(at 228.7 -65.7 0)
			(layer "B.Fab")
			(hide yes)
			(effects
				(font
					(size 1 1)
					(thickness 0.15)
				)
				(justify mirror)
			)
		)
		(property "Voltage" ""
			(at 228.7 -65.7 0)
			(layer "B.Fab")
			(hide yes)
			(effects
				(font
					(size 1 1)
					(thickness 0.15)
				)
				(justify mirror)
			)
		)
		(sheetname "/Peripherals/")
		(sheetfile "peripherals.kicad_sch")
		(attr smd)
		(fp_rect
			(start -0.925 0.47)
			(end 0.925 -0.47)
			(stroke
				(width 0.05)
				(type default)
			)
			(fill no)
			(layer "B.CrtYd")
		)
		(fp_line
			(start 0.504 -0.248)
			(end -0.494 -0.248)
			(stroke
				(width 0.15)
				(type solid)
			)
			(layer "B.Fab")
		)
		(fp_line
			(start -0.494 -0.248)
			(end -0.494 0.25)
			(stroke
				(width 0.15)
				(type solid)
			)
			(layer "B.Fab")
		)
		(fp_line
			(start 0.504 0.25)
			(end 0.504 -0.248)
			(stroke
				(width 0.15)
				(type solid)
			)
			(layer "B.Fab")
		)
		(fp_line
			(start -0.494 0.25)
			(end 0.504 0.25)
			(stroke
				(width 0.15)
				(type solid)
			)
			(layer "B.Fab")
		)
		(fp_text user "Author: Antmicro"
			(at -0.939 -3.399 270)
			(layer "B.Fab")
			(effects
				(font
					(size 0.7 0.7)
					(thickness 0.15)
				)
				(justify left bottom mirror)
			)
		)
		(fp_text user "${REFERENCE}"
			(at -0.939 -4.599 270)
			(layer "B.Fab")
			(effects
				(font
					(size 0.7 0.7)
					(thickness 0.15)
				)
				(justify left bottom mirror)
			)
		)
		(fp_text user "License: Apache-2.0"
			(at -0.939 -5.799 270)
			(layer "B.Fab")
			(effects
				(font
					(size 0.7 0.7)
					(thickness 0.15)
				)
				(justify left bottom mirror)
			)
		)
		(pad "1" smd roundrect
			(at -0.48 0 90)
			(size 0.59 0.64)
			(layers "B.Cu" "B.Mask" "B.Paste")
			(roundrect_rratio 0.25)
			(net 1 "GND")
			(pintype "passive")
		)
		(pad "2" smd roundrect
			(at 0.48 0 90)
			(size 0.59 0.64)
			(layers "B.Cu" "B.Mask" "B.Paste")
			(roundrect_rratio 0.25)
			(net 360 "/Peripherals/USB_DN")
			(pintype "passive")
		)
	)
	(footprint "antmicro-footprints:C_0402_1005Metric"
		(layer "B.Cu")
		(at 136.02 56.37 180)
		(descr "Capacitor SMD 0402")
		(tags "capacitor SMD 0402")
		(property "Reference" "C6"
			(at -0.41 -1.37 0)
			(layer "B.SilkS")
			(effects
				(font
					(size 0.65 0.65)
					(thickness 0.15)
				)
				(justify left bottom mirror)
			)
		)
		(property "Value" "C_100n_0402"
			(at 0 -1.4 0)
			(layer "B.Fab")
			(hide yes)
			(effects
				(font
					(size 0.7 0.7)
					(thickness 0.15)
				)
				(justify left bottom mirror)
			)
		)
		(property "Datasheet" "https://www.murata.com/products/productdetail?partno=GRM155R61H104KE14%23"
			(at 0 0 180)
			(layer "F.Fab")
			(hide yes)
			(effects
				(font
					(size 1.27 1.27)
					(thickness 0.15)
				)
			)
		)
		(property "Description" "SMD Multilayer Ceramic Capacitor, 0.1 µF, 50 V, 0402 [1005 Metric], ± 10%, X5R, GRM Series"
			(at 0 0 180)
			(layer "F.Fab")
			(hide yes)
			(effects
				(font
					(size 1.27 1.27)
					(thickness 0.15)
				)
			)
		)
		(property "Author" "Antmicro"
			(at 272.04 112.74 0)
			(layer "B.Fab")
			(hide yes)
			(effects
				(font
					(size 1 1)
					(thickness 0.15)
				)
				(justify mirror)
			)
		)
		(property "Dielectric" "X5R"
			(at 272.04 112.74 0)
			(layer "B.Fab")
			(hide yes)
			(effects
				(font
					(size 1 1)
					(thickness 0.15)
				)
				(justify mirror)
			)
		)
		(property "License" "Apache-2.0"
			(at 272.04 112.74 0)
			(layer "B.Fab")
			(hide yes)
			(effects
				(font
					(size 1 1)
					(thickness 0.15)
				)
				(justify mirror)
			)
		)
		(property "MPN" "GRM155R61H104KE14D"
			(at 272.04 112.74 0)
			(layer "B.Fab")
			(hide yes)
			(effects
				(font
					(size 1 1)
					(thickness 0.15)
				)
				(justify mirror)
			)
		)
		(property "Manufacturer" "Murata"
			(at 272.04 112.74 0)
			(layer "B.Fab")
			(hide yes)
			(effects
				(font
					(size 1 1)
					(thickness 0.15)
				)
				(justify mirror)
			)
		)
		(property "Val" "100n"
			(at 272.04 112.74 0)
			(layer "B.Fab")
			(hide yes)
			(effects
				(font
					(size 1 1)
					(thickness 0.15)
				)
				(justify mirror)
			)
		)
		(property "Voltage" "50V"
			(at 272.04 112.74 0)
			(layer "B.Fab")
			(hide yes)
			(effects
				(font
					(size 1 1)
					(thickness 0.15)
				)
				(justify mirror)
			)
		)
		(sheetname "/Power Supply/")
		(sheetfile "supply.kicad_sch")
		(attr smd)
		(fp_rect
			(start -0.925 0.47)
			(end 0.925 -0.47)
			(stroke
				(width 0.05)
				(type default)
			)
			(fill no)
			(layer "B.CrtYd")
		)
		(fp_line
			(start 0.504 0.25)
			(end 0.504 -0.248)
			(stroke
				(width 0.15)
				(type solid)
			)
			(layer "B.Fab")
		)
		(fp_line
			(start 0.504 -0.248)
			(end -0.494 -0.248)
			(stroke
				(width 0.15)
				(type solid)
			)
			(layer "B.Fab")
		)
		(fp_line
			(start -0.494 0.25)
			(end 0.504 0.25)
			(stroke
				(width 0.15)
				(type solid)
			)
			(layer "B.Fab")
		)
		(fp_line
			(start -0.494 -0.248)
			(end -0.494 0.25)
			(stroke
				(width 0.15)
				(type solid)
			)
			(layer "B.Fab")
		)
		(fp_text user "License: Apache-2.0"
			(at -0.939 -5.799 0)
			(layer "B.Fab")
			(effects
				(font
					(size 0.7 0.7)
					(thickness 0.15)
				)
				(justify left bottom mirror)
			)
		)
		(fp_text user "Author: Antmicro"
			(at -0.939 -3.399 0)
			(layer "B.Fab")
			(effects
				(font
					(size 0.7 0.7)
					(thickness 0.15)
				)
				(justify left bottom mirror)
			)
		)
		(fp_text user "${REFERENCE}"
			(at -0.939 -4.599 0)
			(layer "B.Fab")
			(effects
				(font
					(size 0.7 0.7)
					(thickness 0.15)
				)
				(justify left bottom mirror)
			)
		)
		(pad "1" smd roundrect
			(at -0.48 0 180)
			(size 0.59 0.64)
			(layers "B.Cu" "B.Mask" "B.Paste")
			(roundrect_rratio 0.25)
			(net 1 "GND")
			(pintype "passive")
		)
		(pad "2" smd roundrect
			(at 0.48 0 180)
			(size 0.59 0.64)
			(layers "B.Cu" "B.Mask" "B.Paste")
			(roundrect_rratio 0.25)
			(net 5 "Vref")
			(pintype "passive")
		)
	)
	(footprint "antmicro-footprints:R_Array_4x0402"
		(layer "B.Cu")
		(at 124.56 62.74 -90)
		(property "Reference" "R44"
			(at -1 1.13 90)
			(layer "B.SilkS")
			(effects
				(font
					(size 0.65 0.65)
					(thickness 0.15)
				)
				(justify left bottom mirror)
			)
		)
		(property "Value" "R_4x51R_0402_array"
			(at -1.5 -2 90)
			(layer "B.Fab")
			(hide yes)
			(effects
				(font
					(size 0.7 0.7)
					(thickness 0.15)
				)
				(justify left bottom mirror)
			)
		)
		(property "Datasheet" "http://industrial.panasonic.com/cdbs/www-data/pdf/AOC0000/AOC0000C14.pdf"
			(at 0 0 270)
			(layer "F.Fab")
			(hide yes)
			(effects
				(font
					(size 1.27 1.27)
					(thickness 0.15)
				)
			)
		)
		(property "Description" "Fixed Network Resistor, 51 ohm, Isolated, 4 Resistors, 0804 [2010 Metric], Convex, ± 5%"
			(at 0 0 270)
			(layer "F.Fab")
			(hide yes)
			(effects
				(font
					(size 1.27 1.27)
					(thickness 0.15)
				)
			)
		)
		(property "Author" "Antmicro"
			(at 61.82 187.3 0)
			(layer "B.Fab")
			(hide yes)
			(effects
				(font
					(size 1 1)
					(thickness 0.15)
				)
				(justify mirror)
			)
		)
		(property "License" "Apache-2.0"
			(at 61.82 187.3 0)
			(layer "B.Fab")
			(hide yes)
			(effects
				(font
					(size 1 1)
					(thickness 0.15)
				)
				(justify mirror)
			)
		)
		(property "MPN" "EXB28V510JX"
			(at 61.82 187.3 0)
			(layer "B.Fab")
			(hide yes)
			(effects
				(font
					(size 1 1)
					(thickness 0.15)
				)
				(justify mirror)
			)
		)
		(property "Manufacturer" "Panasonic"
			(at 61.82 187.3 0)
			(layer "B.Fab")
			(hide yes)
			(effects
				(font
					(size 1 1)
					(thickness 0.15)
				)
				(justify mirror)
			)
		)
		(property "Val" "R_4x51R_0402"
			(at 61.82 187.3 0)
			(layer "B.Fab")
			(hide yes)
			(effects
				(font
					(size 1 1)
					(thickness 0.15)
				)
				(justify mirror)
			)
		)
		(sheetname "/DDR3/")
		(sheetfile "ddr3.kicad_sch")
		(attr smd)
		(fp_line
			(start -1.17 0.5)
			(end -1.17 -0.498)
			(stroke
				(width 0.15)
				(type solid)
			)
			(layer "B.SilkS")
		)
		(fp_line
			(start 1.167 -0.498)
			(end 1.167 0.5)
			(stroke
				(width 0.15)
				(type solid)
			)
			(layer "B.SilkS")
		)
		(fp_rect
			(start -1.2 0.9)
			(end 1.2 -0.9)
			(stroke
				(width 0.05)
				(type solid)
			)
			(fill no)
			(layer "B.CrtYd")
		)
		(fp_line
			(start -1 0.5)
			(end 0.998 0.5)
			(stroke
				(width 0.15)
				(type solid)
			)
			(layer "B.Fab")
		)
		(fp_line
			(start 0.998 0.5)
			(end 0.998 -0.498)
			(stroke
				(width 0.15)
				(type solid)
			)
			(layer "B.Fab")
		)
		(fp_line
			(start -1 -0.498)
			(end -1 0.5)
			(stroke
				(width 0.15)
				(type solid)
			)
			(layer "B.Fab")
		)
		(fp_line
			(start 0.998 -0.498)
			(end -1 -0.498)
			(stroke
				(width 0.15)
				(type solid)
			)
			(layer "B.Fab")
		)
		(pad "1" smd roundrect
			(at -0.802 -0.45 270)
			(size 0.4 0.5)
			(layers "B.Cu" "B.Mask" "B.Paste")
			(roundrect_rratio 0.25)
			(net 157 "/DDR3/DDR3_BA0")
			(pinfunction "R1.1")
			(pintype "passive")
		)
		(pad "2" smd roundrect
			(at -0.272 -0.45 270)
			(size 0.4 0.5)
			(layers "B.Cu" "B.Mask" "B.Paste")
			(roundrect_rratio 0.25)
			(net 167 "/DDR3/DDR3_BA2")
			(pinfunction "R2.1")
			(pintype "passive")
		)
		(pad "3" smd roundrect
			(at 0.27 -0.45 270)
			(size 0.4 0.5)
			(layers "B.Cu" "B.Mask" "B.Paste")
			(roundrect_rratio 0.25)
			(net 168 "/DDR3/~{DDR3_CS}")
			(pinfunction "R3.1")
			(pintype "passive")
		)
		(pad "4" smd roundrect
			(at 0.8 -0.45 270)
			(size 0.4 0.5)
			(layers "B.Cu" "B.Mask" "B.Paste")
			(roundrect_rratio 0.25)
			(net 163 "/DDR3/~{DDR3_WE}")
			(pinfunction "R4.1")
			(pintype "passive")
		)
		(pad "5" smd roundrect
			(at 0.8 0.452 270)
			(size 0.4 0.5)
			(layers "B.Cu" "B.Mask" "B.Paste")
			(roundrect_rratio 0.25)
			(net 6 "Vtt")
			(pinfunction "R4.2")
			(pintype "passive")
		)
		(pad "6" smd roundrect
			(at 0.27 0.452 270)
			(size 0.4 0.5)
			(layers "B.Cu" "B.Mask" "B.Paste")
			(roundrect_rratio 0.25)
			(net 6 "Vtt")
			(pinfunction "R3.2")
			(pintype "passive")
		)
		(pad "7" smd roundrect
			(at -0.272 0.452 270)
			(size 0.4 0.5)
			(layers "B.Cu" "B.Mask" "B.Paste")
			(roundrect_rratio 0.25)
			(net 6 "Vtt")
			(pinfunction "R2.2")
			(pintype "passive")
		)
		(pad "8" smd roundrect
			(at -0.802 0.452 270)
			(size 0.4 0.5)
			(layers "B.Cu" "B.Mask" "B.Paste")
			(roundrect_rratio 0.25)
			(net 6 "Vtt")
			(pinfunction "R1.2")
			(pintype "passive")
		)
	)
	(footprint "antmicro-footprints:C_0402_1005Metric"
		(layer "B.Cu")
		(at 149.5 83.75 -90)
		(descr "Capacitor SMD 0402")
		(tags "capacitor SMD 0402")
		(property "Reference" "C122"
			(at -1.31 -1.33 90)
			(layer "B.SilkS")
			(effects
				(font
					(size 0.65 0.65)
					(thickness 0.15)
				)
				(justify left bottom mirror)
			)
		)
		(property "Value" "C_100n_0402"
			(at 0 -1.4 90)
			(layer "B.Fab")
			(hide yes)
			(effects
				(font
					(size 0.7 0.7)
					(thickness 0.15)
				)
				(justify left bottom mirror)
			)
		)
		(property "Datasheet" "https://www.murata.com/products/productdetail?partno=GRM155R61H104KE14%23"
			(at 0 0 270)
			(layer "F.Fab")
			(hide yes)
			(effects
				(font
					(size 1.27 1.27)
					(thickness 0.15)
				)
			)
		)
		(property "Description" "SMD Multilayer Ceramic Capacitor, 0.1 µF, 50 V, 0402 [1005 Metric], ± 10%, X5R, GRM Series"
			(at 0 0 270)
			(layer "F.Fab")
			(hide yes)
			(effects
				(font
					(size 1.27 1.27)
					(thickness 0.15)
				)
			)
		)
		(property "Author" "Antmicro"
			(at 65.75 233.25 0)
			(layer "B.Fab")
			(hide yes)
			(effects
				(font
					(size 1 1)
					(thickness 0.15)
				)
				(justify mirror)
			)
		)
		(property "Dielectric" "X5R"
			(at 65.75 233.25 0)
			(layer "B.Fab")
			(hide yes)
			(effects
				(font
					(size 1 1)
					(thickness 0.15)
				)
				(justify mirror)
			)
		)
		(property "License" "Apache-2.0"
			(at 65.75 233.25 0)
			(layer "B.Fab")
			(hide yes)
			(effects
				(font
					(size 1 1)
					(thickness 0.15)
				)
				(justify mirror)
			)
		)
		(property "MPN" "GRM155R61H104KE14D"
			(at 65.75 233.25 0)
			(layer "B.Fab")
			(hide yes)
			(effects
				(font
					(size 1 1)
					(thickness 0.15)
				)
				(justify mirror)
			)
		)
		(property "Manufacturer" "Murata"
			(at 65.75 233.25 0)
			(layer "B.Fab")
			(hide yes)
			(effects
				(font
					(size 1 1)
					(thickness 0.15)
				)
				(justify mirror)
			)
		)
		(property "Val" "100n"
			(at 65.75 233.25 0)
			(layer "B.Fab")
			(hide yes)
			(effects
				(font
					(size 1 1)
					(thickness 0.15)
				)
				(justify mirror)
			)
		)
		(property "Voltage" "50V"
			(at 65.75 233.25 0)
			(layer "B.Fab")
			(hide yes)
			(effects
				(font
					(size 1 1)
					(thickness 0.15)
				)
				(justify mirror)
			)
		)
		(sheetname "/Peripherals/")
		(sheetfile "peripherals.kicad_sch")
		(attr smd)
		(fp_rect
			(start -0.925 0.47)
			(end 0.925 -0.47)
			(stroke
				(width 0.05)
				(type default)
			)
			(fill no)
			(layer "B.CrtYd")
		)
		(fp_line
			(start -0.494 0.25)
			(end 0.504 0.25)
			(stroke
				(width 0.15)
				(type solid)
			)
			(layer "B.Fab")
		)
		(fp_line
			(start 0.504 0.25)
			(end 0.504 -0.248)
			(stroke
				(width 0.15)
				(type solid)
			)
			(layer "B.Fab")
		)
		(fp_line
			(start -0.494 -0.248)
			(end -0.494 0.25)
			(stroke
				(width 0.15)
				(type solid)
			)
			(layer "B.Fab")
		)
		(fp_line
			(start 0.504 -0.248)
			(end -0.494 -0.248)
			(stroke
				(width 0.15)
				(type solid)
			)
			(layer "B.Fab")
		)
		(fp_text user "Author: Antmicro"
			(at -0.939 -3.399 90)
			(layer "B.Fab")
			(effects
				(font
					(size 0.7 0.7)
					(thickness 0.15)
				)
				(justify left bottom mirror)
			)
		)
		(fp_text user "${REFERENCE}"
			(at -0.939 -4.599 90)
			(layer "B.Fab")
			(effects
				(font
					(size 0.7 0.7)
					(thickness 0.15)
				)
				(justify left bottom mirror)
			)
		)
		(fp_text user "License: Apache-2.0"
			(at -0.939 -5.799 90)
			(layer "B.Fab")
			(effects
				(font
					(size 0.7 0.7)
					(thickness 0.15)
				)
				(justify left bottom mirror)
			)
		)
		(pad "1" smd roundrect
			(at -0.48 0 270)
			(size 0.59 0.64)
			(layers "B.Cu" "B.Mask" "B.Paste")
			(roundrect_rratio 0.25)
			(net 1 "GND")
			(pintype "passive")
		)
		(pad "2" smd roundrect
			(at 0.48 0 270)
			(size 0.59 0.64)
			(layers "B.Cu" "B.Mask" "B.Paste")
			(roundrect_rratio 0.25)
			(net 325 "USB_POWER_IN")
			(pintype "passive")
		)
	)
)
